# T6G (Grand Teton) — schematic netlist excerpt (pin names and nets, part order shuffled) for the footprints in the layout excerpt that follows; sources: Cadence DE-HDL packaged netlist, KiCad conversion of 04192023_DAF0TMB3IC0_F0TG_MB_C_brd_V02_OCP.brd

C681  Q_CAP_DIFFBUS  DIFF BUS_0.22UF 6.3V 20% X6S  pkg C0201  page 67 : \1\ = P5E_CPU1_G1_TX_C_DP<14> ; \2\ = P5E_CPU1_G1_TX_DP<14>
R713  Q_RES  10K 1% EMPTY  pkg 0402LF  page 238 : A = P3V3_AUX ; B = MB_FRU_ADDR2
PC293_4  Q_CAP  0.1UF 25V 10% X7R  pkg 0402  page 212 : A = SW_P12V_AUX_PVDDCR_CPU0_P1_FLT ; B = GND

(kicad_pcb
	(version 20260206)
	(generator "pcbnew")
	(generator_version "10.0")
	(general
		(thickness 1.6)
		(legacy_teardrops no)
	)
	(paper "A4")
	(title_block
		(title "04192023_DAF0TMB3IC0_F0TG_MB_C_brd_V02_OCP.brd")
		(comment 1 "Grand Teton / footprints 4815-4817 of 8354")
	)
	(layers
		(0 "F.Cu" signal "TOP")
		(4 "In1.Cu" signal "GND")
		(6 "In2.Cu" signal "IN1")
		(8 "In3.Cu" signal "GND1")
		(10 "In4.Cu" signal "IN2")
		(12 "In5.Cu" signal "GND2")
		(14 "In6.Cu" signal "IN3")
		(16 "In7.Cu" signal "GND3")
		(18 "In8.Cu" signal "VCC")
		(20 "In9.Cu" signal "VCC1")
		(22 "In10.Cu" signal "GND4")
		(24 "In11.Cu" signal "IN4")
		(26 "In12.Cu" signal "GND5")
		(28 "In13.Cu" signal "IN5")
		(30 "In14.Cu" signal "GND6")
		(32 "In15.Cu" signal "IN6")
		(34 "In16.Cu" signal "GND7")
		(2 "B.Cu" signal "BOTTOM")
		(9 "F.Adhes" user "F.Adhesive")
		(11 "B.Adhes" user "B.Adhesive")
		(13 "F.Paste" user "Package Geometry/Pastemask Top")
		(15 "B.Paste" user "Package Geometry/Pastemask Bottom")
		(5 "F.SilkS" user "Ref Des/Silkscreen Top")
		(7 "B.SilkS" user "Ref Des/Silkscreen Bottom")
		(1 "F.Mask" user "Board Geometry/Soldermask Top")
		(3 "B.Mask" user "Board Geometry/Soldermask Bottom")
		(17 "Dwgs.User" user "User.Drawings")
		(19 "Cmts.User" user "User.Comments")
		(21 "Eco1.User" user "User.Eco1")
		(23 "Eco2.User" user "User.Eco2")
		(25 "Edge.Cuts" user "Board Geometry/Outline")
		(27 "Margin" user)
		(31 "F.CrtYd" user "Package Geometry/Place Bound Top")
		(29 "B.CrtYd" user "Package Geometry/Place Bound Bottom")
		(35 "F.Fab" user "Ref Des/Assembly Top")
		(33 "B.Fab" user "Ref Des/Assembly Bottom")
	)
	(footprint ""
		(layer "F.Cu")
		(at 102.811834 -176.438052 90)
		(property "Reference" "PC293_4"
			(at 0 0 90)
			(layer "F.SilkS")
			(hide yes)
			(effects
				(font
					(size 1.27 1.27)
				)
			)
		)
		(property "Value" ""
			(at 0 0 90)
			(layer "F.Fab")
			(effects
				(font
					(size 1.27 1.27)
				)
			)
		)
		(duplicate_pad_numbers_are_jumpers no)
		(fp_line
			(start 0.7874 -0.4064)
			(end 0.7874 0.4064)
			(stroke
				(width 0.1524)
				(type default)
			)
			(layer "F.SilkS")
		)
		(fp_line
			(start -0.7874 -0.4064)
			(end 0.7874 -0.4064)
			(stroke
				(width 0.1524)
				(type default)
			)
			(layer "F.SilkS")
		)
		(fp_line
			(start 0.7874 0.4064)
			(end -0.7874 0.4064)
			(stroke
				(width 0.1524)
				(type default)
			)
			(layer "F.SilkS")
		)
		(fp_line
			(start -0.7874 0.4064)
			(end -0.7874 -0.4064)
			(stroke
				(width 0.1524)
				(type default)
			)
			(layer "F.SilkS")
		)
		(fp_line
			(start -0.12065 -0.305054)
			(end -0.12065 -0.2794)
			(stroke
				(width 0.1)
				(type default)
			)
			(layer "F.Fab")
		)
		(fp_line
			(start -0.67945 -0.305054)
			(end -0.12065 -0.305054)
			(stroke
				(width 0.1)
				(type default)
			)
			(layer "F.Fab")
		)
		(fp_line
			(start 0.67945 -0.3048)
			(end 0.67945 0.3048)
			(stroke
				(width 0.1)
				(type default)
			)
			(layer "F.Fab")
		)
		(fp_line
			(start 0.12065 -0.3048)
			(end 0.67945 -0.3048)
			(stroke
				(width 0.1)
				(type default)
			)
			(layer "F.Fab")
		)
		(fp_line
			(start 0.12065 -0.2794)
			(end 0.12065 -0.3048)
			(stroke
				(width 0.1)
				(type default)
			)
			(layer "F.Fab")
		)
		(fp_line
			(start -0.12065 -0.2794)
			(end 0.12065 -0.2794)
			(stroke
				(width 0.1)
				(type default)
			)
			(layer "F.Fab")
		)
		(fp_line
			(start 0.120396 0.2794)
			(end -0.12065 0.2794)
			(stroke
				(width 0.1)
				(type default)
			)
			(layer "F.Fab")
		)
		(fp_line
			(start -0.12065 0.2794)
			(end -0.12065 0.3048)
			(stroke
				(width 0.1)
				(type default)
			)
			(layer "F.Fab")
		)
		(fp_line
			(start 0.67945 0.3048)
			(end 0.120396 0.3048)
			(stroke
				(width 0.1)
				(type default)
			)
			(layer "F.Fab")
		)
		(fp_line
			(start 0.120396 0.3048)
			(end 0.120396 0.2794)
			(stroke
				(width 0.1)
				(type default)
			)
			(layer "F.Fab")
		)
		(fp_line
			(start -0.12065 0.3048)
			(end -0.67945 0.3048)
			(stroke
				(width 0.1)
				(type default)
			)
			(layer "F.Fab")
		)
		(fp_line
			(start -0.67945 0.3048)
			(end -0.67945 -0.305054)
			(stroke
				(width 0.1)
				(type default)
			)
			(layer "F.Fab")
		)
		(pad "1" smd circle
			(at -0.40005 0 90)
			(size 0 0)
			(layers "F.Cu" "F.Mask" "F.Paste")
			(net "SW_P12V_AUX_PVDDCR_CPU0_P1_FLT")
		)
		(pad "2" smd circle
			(at 0.40005 0 90)
			(size 0 0)
			(layers "F.Cu" "F.Mask" "F.Paste")
			(net "GND")
		)
	)
	(footprint ""
		(layer "F.Cu")
		(at 19.216878 -17.623536 90)
		(property "Reference" "C681"
			(at 0 0 90)
			(layer "F.SilkS")
			(hide yes)
			(effects
				(font
					(size 1.27 1.27)
				)
			)
		)
		(property "Value" ""
			(at 0 0 90)
			(layer "F.Fab")
			(effects
				(font
					(size 1.27 1.27)
				)
			)
		)
		(duplicate_pad_numbers_are_jumpers no)
		(fp_line
			(start 0.299974 -0.150114)
			(end 0.299974 0.150114)
			(stroke
				(width 0.1)
				(type default)
			)
			(layer "F.Fab")
		)
		(fp_line
			(start -0.299974 -0.150114)
			(end 0.299974 -0.150114)
			(stroke
				(width 0.1)
				(type default)
			)
			(layer "F.Fab")
		)
		(fp_line
			(start 0.299974 0.150114)
			(end -0.299974 0.150114)
			(stroke
				(width 0.1)
				(type default)
			)
			(layer "F.Fab")
		)
		(fp_line
			(start -0.299974 0.150114)
			(end -0.299974 -0.150114)
			(stroke
				(width 0.1)
				(type default)
			)
			(layer "F.Fab")
		)
		(pad "1" smd rect
			(at -0.2667 0 90)
			(size 0.3048 0.381)
			(layers "F.Cu" "F.Mask" "F.Paste")
			(net "P5E_CPU1_G1_TX_C_DP<14>")
		)
		(pad "2" smd rect
			(at 0.2667 0 90)
			(size 0.3048 0.381)
			(layers "F.Cu" "F.Mask" "F.Paste")
			(net "P5E_CPU1_G1_TX_DP<14>")
		)
	)
	(footprint ""
		(layer "F.Cu")
		(at 305.162458 -116.891308)
		(property "Reference" "R713"
			(at 0 0 0)
			(layer "F.SilkS")
			(hide yes)
			(effects
				(font
					(size 1.27 1.27)
				)
			)
		)
		(property "Value" ""
			(at 0 0 0)
			(layer "F.Fab")
			(effects
				(font
					(size 1.27 1.27)
				)
			)
		)
		(duplicate_pad_numbers_are_jumpers no)
		(fp_line
			(start -0.7874 -0.4064)
			(end 0.7874 -0.4064)
			(stroke
				(width 0.1524)
				(type default)
			)
			(layer "F.SilkS")
		)
		(fp_line
			(start -0.7874 0.4064)
			(end -0.7874 -0.4064)
			(stroke
				(width 0.1524)
				(type default)
			)
			(layer "F.SilkS")
		)
		(fp_line
			(start 0.7874 -0.4064)
			(end 0.7874 0.4064)
			(stroke
				(width 0.1524)
				(type default)
			)
			(layer "F.SilkS")
		)
		(fp_line
			(start 0.7874 0.4064)
			(end -0.7874 0.4064)
			(stroke
				(width 0.1524)
				(type default)
			)
			(layer "F.SilkS")
		)
		(fp_line
			(start -0.67945 -0.305054)
			(end -0.12065 -0.305054)
			(stroke
				(width 0.1)
				(type default)
			)
			(layer "F.Fab")
		)
		(fp_line
			(start -0.67945 0.3048)
			(end -0.67945 -0.305054)
			(stroke
				(width 0.1)
				(type default)
			)
			(layer "F.Fab")
		)
		(fp_line
			(start -0.12065 -0.305054)
			(end -0.12065 -0.2794)
			(stroke
				(width 0.1)
				(type default)
			)
			(layer "F.Fab")
		)
		(fp_line
			(start -0.12065 -0.2794)
			(end 0.12065 -0.2794)
			(stroke
				(width 0.1)
				(type default)
			)
			(layer "F.Fab")
		)
		(fp_line
			(start -0.12065 0.2794)
			(end -0.12065 0.3048)
			(stroke
				(width 0.1)
				(type default)
			)
			(layer "F.Fab")
		)
		(fp_line
			(start -0.12065 0.3048)
			(end -0.67945 0.3048)
			(stroke
				(width 0.1)
				(type default)
			)
			(layer "F.Fab")
		)
		(fp_line
			(start 0.120396 0.2794)
			(end -0.12065 0.2794)
			(stroke
				(width 0.1)
				(type default)
			)
			(layer "F.Fab")
		)
		(fp_line
			(start 0.120396 0.3048)
			(end 0.120396 0.2794)
			(stroke
				(width 0.1)
				(type default)
			)
			(layer "F.Fab")
		)
		(fp_line
			(start 0.12065 -0.3048)
			(end 0.67945 -0.3048)
			(stroke
				(width 0.1)
				(type default)
			)
			(layer "F.Fab")
		)
		(fp_line
			(start 0.12065 -0.2794)
			(end 0.12065 -0.3048)
			(stroke
				(width 0.1)
				(type default)
			)
			(layer "F.Fab")
		)
		(fp_line
			(start 0.67945 -0.3048)
			(end 0.67945 0.3048)
			(stroke
				(width 0.1)
				(type default)
			)
			(layer "F.Fab")
		)
		(fp_line
			(start 0.67945 0.3048)
			(end 0.120396 0.3048)
			(stroke
				(width 0.1)
				(type default)
			)
			(layer "F.Fab")
		)
		(pad "1" smd circle
			(at -0.40005 0)
			(size 0 0)
			(layers "F.Cu" "F.Mask" "F.Paste")
			(net "P3V3_AUX")
		)
		(pad "2" smd circle
			(at 0.40005 0)
			(size 0 0)
			(layers "F.Cu" "F.Mask" "F.Paste")
			(net "MB_FRU_ADDR2")
		)
	)
)
